TITLE: Bill of Materials
DATE: 08/19/2021
DESIGN: scm
TEMPLATE: c:\cadence\spb_17.2\share\cdssetup\template.bom
CALLOUT: bom.callouts

S.No.,PART_NUMBER,DESCRIPTION,MATERIAL,Qty,MANUFTR,MANUF_PN,Ref Des,QPN,LIFECYCLE,STANDARD
0,AJ026000T04,IC CTRL(624P)AST2600A1-GP(TFBGA),IC,1,APD,AST2600A1-GP,U5,?,?,?
1,AJ10M020T00,IC OTHER(169P)10M02SCU169C8G(UBGA),IC,1,INT,10M02SCU169C8G,U25,?,?,?
2,AKD5FGUT502,IC SDRAM(96P)K4A8G165WC-BCTD(FBGA)QBCON,IC,1,SAM,K4A8G165WC-BCTD,U1,?,?,?
3,AKE30Z0K610,IC(8P)M24128-BWDW6TP(TSSOP),IC,1,SGT,M24128-BWDW6TP,U19,?,?,?
4,AL0000750E3,IC(8P) TMP75AIDGKR (MSOP),IC,1,TIC,TMP75AIDGKR,U4,?,?,?
5,AL000234001,IC OTHER(12P)FT234XD-R(DFN),IC,1,FTI,FT234XD-R,U17,?,?,?
6,AL000257K00,IC OTHER(16P)IDTQS3VH257PAG(TSSOP),IC,2,?,IDTQS3VH257PAG,"U21,U30",?,?,?
7,AL000695001,IC CTRL(13P)NB695GD-Z(QFN-13),IC,2,MPS,NB695GD-Z,"PU41,PU42",?,?,?
8,AL002553002,IC OTHER(6P) TPS2553DBVR-1(SOT23),IC,1,TIC,TPS2553DBVR-1,U10,?,?,?
9,AL002G07006,IC(6P) SN74LVC2G07DCKR(SC70-6),IC,3,?,SN74LVC2G07DCKR,"U6,U24,U47",?,?,?
10,AL006126001,IC OTHER(42P) HD3SS6126RUAR (WQFN),IC,1,TIC,HD3SS6126RUAR,U22,?,?,?
11,AL008626000,IC CTRL(14P)MPQ8626GD-Z(QFN),IC,1,MPS,MPQ8626GD-Z,PU1,?,?,?
12,AL008633007,IC CTRL(21P)MPQ8633AGLE-C807-Z(QFN),IC,1,MPS,MPQ8633AGLE-C807-Z,PU38,?,?,?
13,AL009059000,IC OTHER(10P) RT9059GQW(WDFN),IC,2,RTK,RT9059GQW,"PU39,PU40",?,?,?
14,AL009517K00,IC OTHER (8P) PCA9517ADP(TSSOP8),IC,1,?,?,U37,?,?,?
15,AL022811000,IC OTHER(5P)AP22811AW5-7(SOT25),IC,1,DDS,AP22811AW5-7,U14,?,?,?
16,AL022965000,IC OTHER (8P) TPS22965DSGR(SON),IC,1,TIC,TPS22965DSGR,U15,?,?,?
17,AL054612B00,IC OTHER(48P) BCM54612EB1KMLG(MLP),IC,1,BCM,BCM54612EB1KMLG,U7,?,?,?
18,AL1G0007016,IC OTHER(5P)SN74LVC1G07DCKR(SOT),IC,1,TIC,SN74LVC1G07DCKR,U13,?,?,?
19,AL1G0007016,IC OTHER(5P)SN74LVC1G07DCKR(SOT),EMPTY,1,TIC,SN74LVC1G07DCKR,U44,?,?,?
20,AL1G0007024,IC(5P) SN74LVC1G07DCKR(SOP),IC,1,?,?,U23,?,?,?
21,AL1G0017003,IC(5P) SN74LVC1G17DCKR (SC-70),IC,1,TIC,SN74LVC1G17DCKR,U46,?,?,?
22,AL1G0017K01,IC OTHER(5P) 74LVC1G17GW(TSSOP),IC,1,NXP,74LVC1G17GW,U32,?,?,?
23,AL1G0126007,IC(5P) 74HC1G126GW(SOT353)EP,IC,4,PHI,74HC1G126GW,"U26,U29,U33,U36",?,?,?
24,AL1G3157001,IC OTHER(6P) SN74LVC1G3157DCKR(SC70-6),IC,4,TIC,SN74LVC1G3157DCKR,"U2,U3,U41,U42",?,?,?
25,AL2EUSB3000,IC OTHER(3P) TPD2EUSB30DRTR (SOT),IC,3,TIC,TPD2EUSB30DRTR,"U18,U27,U39",?,?,?
26,AL380833000,IC OTHER(6P) TPS3808G33DBVR(SOT23)HF,IC,1,TIC,TPS3808G33DBVR,U43,?,?,?
27,AL5V0U2X000,IC OTHER (4P) PRTR5V0U2X (SOT143B),IC,1,NXP,PRTR5V0U2X,U38,?,?,?
28,ALVC1G07002,IC(5P) 74LVC1G07GW(SOT353),IC,1,PHI,74LVC1G07GW,U31,?,?,?
29,BA0390400H0,"TRANS SMD MMBT3904-7-F(40V,200MA,8W)",IC,2,DDS,MMBT3904-7-F,"Q1,Q3",?,Comp-Approve,End of Design
30,BAM01230014,TRANS MOSFET BSS123-7-F(100V.170MA),IC,1,DDS,BSS123-7-F,Q7,?,?,?
31,BAM138K0000,"TRANS MOS BSS138K(50V,0.22A,0.35W)",IC,1,?,BSS138K,U12,?,?,?
32,BAM23050027,"TRAN P-MOSFET AP2305GN-20V,1.38W(SOT-23)",EMPTY,1,AVP,AP2305GN,Q4,?,?,?
33,BAM41410005,"TRANS MOS NTGS4141NT1G(30V,7.0A,TSOP6)",IC,1,ONS,NTGS4141NT1G,Q5,?,Comp-Approve,End of Design
34,BAM69680000,"TRANS MOS DMG6968U-7(20V,6.5A,1.3W)SOT23",IC,1,DDS,DMG6968U-7,Q10,?,Comp-Approve,End of Design
35,BAM70020047,"TRANS MOS 2N7002KDW(60V115MA,0.2W)SOT363",IC,2,PJT,2N7002KDW,"Q2,Q12",?,?,?
36,BAM70020062,"TRANS MOS NX7002AK(60V,0.19A,0.325W)SMD",IC,1,NXP,NX7002AK,Q11,?,Comp-Approve,End of Design
37,BAM70020068,"TRANS MOS 2N7002A-7(60V,0.115A,0.25W)",IC,2,DDS,2N7002A-7,"Q6,Q8",?,?,?
38,BC000340033,"DIODE SMD SDMK0340L-7-F(40V,30MA)",IC,1,?,?,D17,?,?,?
39,BC0161SS000,"DIODE SMD RB161SS-20T2R(30V,1A)SCHOTTKY",IC,1,ROH,RB161SS-20T2R,D16,?,Comp-Approve,End of Design
40,BC01DBVR000,"DIODE SMD TPD4E001DBVR(5.5V,0.1UA)SOT23",IC,3,TIC,TPD4E001DBVR,"U16,U34,U35",?,?,?
41,BC01DBVR000,"DIODE SMD TPD4E001DBVR(5.5V,0.1UA)SOT23",EMPTY,2,TIC,TPD4E001DBVR,"U8,U9",?,?,?
42,BC0BAS70Z01,"DIODE SMD BAS70-05-7-F(70V,SHTKY,SOT-23)",IC,1,DDS,BAS70-05-7-F,U48,?,Comp-Approve,End of Design
43,BCBAT54CZ04,"DIODE SMD BAT54C(30V,0.2A,SCHOTTKY)",IC,1,PJT,BAT54C,U11,?,Comp-Approve,End of Design
44,BCSS0530Z00,"DIODE SMD SS0530(30V,0.5A)SOD-123",IC,1,PJT,SS0530,D11,?,?,?
45,BCSS0530Z00,"DIODE SMD SS0530(30V,0.5A)SOD-123",EMPTY,1,PJT,SS0530,D9,?,?,?
46,BCZA462AZ01,"DIODE SMD BZA462A(6.2V,100MA,SOT457)",IC,1,PHI,BZA462A,D10,?,?,?
47,BCZA462AZ01,"DIODE SMD BZA462A(6.2V,100MA,SOT457)",EMPTY,1,PHI,BZA462A,D12,?,?,?
48,BEBL0261Z00,LED SMD(2P)BLUE(12-215/BHC-YMNRY/3C),IC,2,?,12-215/BHC-YMNRY/3C,"D14,D15",?,?,?
49,BEGR0278Z00,LED SMD(2P) GREEN(19-213/GVC-AMNB/3T),IC,5,?,19-213/GVC-AMNB/3T,"D0-D3,D8",?,?,?
50,BERD0034Z07,LED SMD(2P) RED (19-217/R6C-P1Q2/3T),IC,4,?,19-217/R6C-P1Q2/3T,D4-D7,?,?,?
51,BF625000023,"OSC SMD 25MHZ(+-25PPM,3.3V)7X25000018",MISC,2,TXC,7X25000018,"OSC1,OSC2",?,?,?
52,BG625000802,"XTAL SMD 25MHZ(+-20PPM,20PF)7M25020008",MISC,1,TXC,7M25020008,Y1,?,?,?
53,CH0106F0B00,CHIP0402,NPO,5,?,?,"C205-C207,C211,C212",?,?,?
54,CH01206JB05,CAP CHIP 12P 50V(+-5%.C0G.0402),C0G,2,?,?,"C141,C145",?,?,?
55,CH02206JB08,CHIP0402,EMPTY,1,?,?,C152,?,?,?
56,CH0336F0B00,"CAP CHIP 33P 50V(+-1%,C0G,0402)",C0G,3,?,?,C208-C210,?,?,?
57,CH06806JB01,CAP CHIP 68P 50V(+-5%.COG.0402),COG,1,?,?,PC272,?,?,?
58,CH11006JB00,"CAP CHIP 100P 50V(+-5%,NPO,0402)",NPO,6,?,?,"C9,C165-C167,C275,PC239",?,?,?
59,CH11006JB18,CAP CHIP 100P 50V(+-5%.X7R.0402),EMPTY,2,?,?,"C213,C214",?,Comp-Approve,End of Design
60,CH14706KB18,CHIP0402,X7R,5,?,?,"C172,C178,C179,C324,C326",?,?,?
61,CH22206KB16,"CAP CHIP 2200P 50V(+-10%,X7R,0402)",X7R,1,?,?,C63,?,?,?
62,CH2336K1B12,CHIP0402,X7R,1,?,?,PC273,?,?,?
63,CH2474K1B08,"CAP CHIP 4700P 25V(+-10%,X7R,0402)MUR",EMPTY,1,?,?,C223,?,?,?
64,CH30106KB19,"CAP CHIP 0.001U 50V(10%,X7R,0402)",X7R,6,?,?,"C150,C151,C153-C156",?,Comp-Release Qty,End of Design
65,CH31006KB18,"CAP CHIP 0.01U 50V(+-10%,X7R,0402)",X7R,10,?,?,"C133-C138,C163,C164,C170,C246",?,?,?
66,CH31006KB18,"CAP CHIP 0.01U 50V(+-10%,X7R,0402)",EMPTY,3,?,?,"C21,C142,C169",?,?,?
67,CH4104K1B00,"CAP CHIP 0.1U 25V(+-10%,X7R,0402)",X7R,171,?,?,"C6-C8,C10,C13,C14,C17-C20,C23-C29,C31,C33,C34,C36,C37,C39,C41,C45,C49-C51,C54,C57,C59,C65,C66,C68-C74,C76,C77,C79,C81-C89,C91-C103,C105,C107,C109,C112,C130,C139,C140,C144,C146-C149,C157-C160,C168,C173-C175,C180,C182,C185-C187,C189,C191,C192,C197,C200-C203,C217,C219,C221,C222,C225,C236,C237,C240-C242,C245,C249-C251,C253-C255,C261,C263-C266,C268,C269,C272,C274,C276,C278-C280,C283-C285,C287,C289,C290,C292-C303,C305,C307-C309,C311,C314,C318,C321,C328,C331-C334,PC205,PC210,PC212,PC223,PC225,PC235,PC249,PC253,PC255,PC263,PC266,PC271",?,?,?
68,CH4104K1B00,"CAP CHIP 0.1U 25V(+-10%,X7R,0402)",EMPTY,4,?,?,"C22,C238,C239,C304",?,?,?
69,CH4223K1B00,"CAP CHIP 0.22U 16V(10%,X7R,0402)",X7R,5,?,?,"C12,PC216,PC224,PC254,PC264",?,Comp-Approve,End of Design
70,CH4223K1B00,"CAP CHIP 0.22U 16V(10%,X7R,0402)",EMPTY,1,?,?,C229,?,Comp-Approve,End of Design
71,CH5103K1900,CHIP0603,EMPTY,1,?,?,C204,?,Comp-Approve,End of Design
72,CH5103K9B00,CHIP0402,EMPTY,4,?,?,"C181,C267,C270,C273",?,Comp-Approve,End of Design
73,CH5104KEB02,"CAP CHIP 1UF 25V(+-10%,X6S,0402)",X6S,65,?,?,"C2-C5,C30,C32,C35,C38,C43,C46-C48,C52,C53,C56,C58,C60-C62,C64,C67,C75,C78,C80,C90,C104,C106,C108,C110,C111,C114-C117,C119,C122,C127-C129,C161,C176,C194-C196,C198,C199,C216,C243,C244,C247,C252,C260,C271,C277,C281,C282,C286,C288,C291,PC208,PC221,PC233,PC243,PC250,PC260",?,?,?
74,CH5472K9B00,"CAP CHIP 4.7U 10V(+-10%,X5R,0402)",X5R,5,?,?,"C40,C44,C347,C348,C350",?,?,?
75,CH5474KE906,"CAP CHIP 4.7UF 25V(+-10%,X6S,0603)",X6S,1,?,?,C1,?,?,?
76,CH6101MEB01,"CAP CHIP 10UF 6.3V(+-20%,X6S,0402)",X6S,7,?,?,"C15,C16,C143,C215,C224,C248,C262",?,?,?
77,CH6103ME902,"CAP CHIP 10U 16V(+-20%,X6S,0603)",X6S,6,?,?,"C162,C188,C190,C193,C218,C220",?,?,?
78,CH6104KEA00,"CAP CHIP 10U 25V(+-10%,X6S,0805,H1.25)",X6S,8,?,?,"PC237,PC242,PC248,PC251,PC252,PC261,PC262,PC307",?,?,?
79,CH6221M9B01,"CAP CHIP 22U 6.3V(+-20%,X5R,0402)",X5R,2,?,?,"C346,C349",?,Comp-Approve,End of Design
80,CH6221ME900,"CAP CHIP 22U 6.3V(+-20%,X6S,0603)",X6S,7,?,?,"C42,C55,C118,C121,C123,C124,C126",?,?,?
81,CH6222M9901,"CAP CHIP 22UF 10V(+-20%,X5R,0603)",X5R,7,?,?,"C113,C120,C125,C131,C132,C183,C184",?,?,?
82,CH6222MEA00,"CAP CHIP 22U 10V(+-20%,X6S,0805)",X6S,9,?,?,"C171,PC213-PC215,PC217,PC226-PC229",?,?,?
83,CH6223MEA01,"CAP CHIP 22UF 16V(+-20%,X6S,0805)MUR",X6S,4,?,?,"PC206,PC207,PC218,PC219",?,?,?
84,CH6224M9A00,"CAP CHIP 22U 25V(+-20%,X5R,0805)",X5R,2,?,?,"C329,C330",?,?,?
85,CH622KMEA01,CHIP0805,X6S,8,?,?,"PC256-PC259,PC267-PC270",?,Comp-Approve,End of Design
86,CH6472M9200,"CAP CHIP 47U 10V(+-20%,X5R,1206)  ",X5R,2,?,?,"C177,C327",?,Comp-Approve,End of Design
87,CS-5102JB02,RES CHIP 5.1 1/16W +-5%(0402)EF,CHIP,2,?,?,"PR539,PR541",?,?,?
88,CS00002JB13,RES CHIP 0 1/16W +-5%(0402)EF,CHIP,149,?,?,"PR193,PR274,R2,R3,R18-R21,R24,R26,R30,R35,R39,R43,R49,R51,R83,R86,R95,R97-R100,R106,R109,R110,R113,R135,R141,R155,R207,R213,R216-R218,R220,R231,R271,R272,R275-R277,R279,R281,R282,R292-R294,R297,R300,R302,R303,R315-R323,R379-R382,R384-R386,R393,R397,R399,R406,R447,R451,R453,R454,R456,R457,R498-R500,R503,R505,R519,R520,R527,R528,R542,R564-R566,R571-R579,R587,R616,R626,R632,R634,R636,R637,R666,R668-R676,R693,R695-R698,R700-R703,R707,R708,R720-R723,R726-R729,R731-R734,R746,R747,R771,R772,R779,R783,R822,R5650,R5660",?,Comp-Approve,End of Design
89,CS00002JB13,RES CHIP 0 1/16W +-5%(0402)EF,EMPTY,28,?,?,"PR205,PR275,R1,R63,R64,R154,R156,R208,R214,R232,R278,R280,R301,R432,R450,R529,R530,R581,R585,R711,R719,R748,R764,R780-R782,R784,R800",?,Comp-Approve,End of Design
90,CS00003J910,RES CHIP 0 1/10W +-5% (0603)EF,EMPTY,3,?,?,"R27,R645,R646",?,Comp-Approve,End of Design
91,CS02202FB02,RES CHIP 22 1/16W +-1%(0402)EF,CHIP,8,?,?,"R286,R288,R538,R539,R628-R631",?,Comp-Approve,End of Design
92,CS02741FE02,RES CHIP 27.4 1/20W +-1%(0201)EF,CHIP,2,?,?,"R402,R403",?,?,?
93,CS03322FB03,RES CHIP 33.2 1/16W +-1%(0402)EF,CHIP,233,?,?,"R28,R29,R33,R36,R37,R46,R47,R52-R54,R60,R65,R71,R84,R85,R90,R93,R102,R104,R111,R112,R114,R119-R121,R123,R128-R133,R137-R139,R142-R144,R146-R148,R150-R153,R157-R160,R162,R165,R166,R168,R170-R187,R198-R201,R215,R221-R225,R236,R237,R242,R243,R263,R270,R394,R404,R405,R407-R410,R420,R421,R423-R427,R433-R437,R439,R440,R442-R445,R448,R449,R458-R463,R465,R466,R468-R477,R479-R486,R489,R494,R501,R509-R518,R522,R524-R526,R531,R533-R537,R540,R541,R545-R551,R553,R554,R561,R562,R567,R570,R580,R582-R584,R589,R590,R594,R635,R638,R639,R643,R644,R690,R691,R704,R705,R713,R715,R718,R724,R725,R750,R757,R759-R763,R766,R767,R769,R773,R799,R801-R804,R807,R812,R813,R824-R826,R833,R836,R837,R840,R841,R852,R859-R864",?,Comp-Approve,End of Design
94,CS03322FB03,RES CHIP 33.2 1/16W +-1%(0402)EF,EMPTY,13,?,?,"R80,R96,R107,R677-R682,R688,R689,R752,R827",?,Comp-Approve,End of Design
95,CS04992FB07,RES CHIP 49.9 1/16W +-1%(0402)EF,CHIP,2,?,?,"R108,R192",?,Comp-Approve,End of Design
96,CS06042FB03,RES CHIP 60.4 1/16W +-1%(0402)EF,CHIP,2,?,?,"R7,R8",?,Comp-Approve,End of Design
97,CS11002FB07,RES CHIP 100 1/16W +-1%(0402)EF,EMPTY,5,?,?,"R125,R417,R743-R745",?,Comp-Approve,End of Design
98,CS11002FB07,RES CHIP 100 1/16W +-1%(0402)EF,CHIP,11,?,?,"R94,R134,R411-R413,R415,R419,R431,R506,R507,R694",?,Comp-Approve,End of Design
99,CS11202FB02,RES CHIP 120 1/16W +-1%(0402)EF,CHIP,48,?,?,"R326-R349,R351-R374",?,Comp-Approve,End of Design
100,CS11202FB02,RES CHIP 120 1/16W +-1%(0402)EF,EMPTY,2,?,?,"R350,R375",?,Comp-Approve,End of Design
101,CS11502FB07,RES CHIP 150 1/16W +-1%(0402)EF,CHIP,6,?,?,"R22,R23,R25,R87-R89",?,Comp-Approve,End of Design
102,CS12202FB04,RES CHIP 220 1/16W +-1%(0402)EF,CHIP,3,?,?,R304-R306,?,?,?
103,CS12402FB01,RES CHIP 240 1/16W +-1%(0402)EF,CHIP,2,?,?,"R6,R127",?,Comp-Approve,End of Design
104,CS13302FB00,RES CHIP 330 1/16W +-1%(0402)EF,CHIP,1,?,?,R167,?,Comp-Approve,End of Design
105,CS14992FB06,RES CHIP 499 1/16W +-1%(0402)EF,CHIP,1,?,?,R287,?,Comp-Approve,End of Design
106,CS16652FB00,RES CHIP 665 1/16W +-1%(0402)EF,CHIP,1,?,?,R793,?,Comp-Approve,End of Design
107,CS17502FB03,RES CHIP 750 1/16W +-1%(0402)EF,CHIP,8,?,?,R597-R604,?,Comp-Approve,End of Design
108,CS21002FB06,RES CHIP 1K 1/16W +-1%(0402)EF,CHIP,13,?,?,"R4,R5,R15,R210,R324,R325,R568,R569,R735,R736,R775,R795,R796",?,Comp-Approve,End of Design
109,CS21002FB06,RES CHIP 1K 1/16W +-1%(0402)EF,EMPTY,5,?,?,"R73,R77,R633,R684,R685",?,Comp-Approve,End of Design
110,CS21242FB04,RES CHIP 1.24K 1/16W +-1%(0402)EF,CHIP,1,?,?,R400,?,Comp-Approve,End of Design
111,CS21501FE14,RES CHIP 1.5K 1/20W +-1%(0201)EF,CHIP,2,?,?,"R401,R756",?,?,?
112,CS21502FB07,RES CHIP 1.5K 1/16W +-1%(0402)EF,EMPTY,1,?,?,R283,?,Comp-Approve,End of Design
113,CS21502FB07,RES CHIP 1.5K 1/16W +-1%(0402)EF,CHIP,1,?,?,R285,?,Comp-Approve,End of Design
114,CS21692FB04,RES CHIP 1.69K 1/16W +-1%(0402)EF,CHIP,1,?,?,R791,?,Comp-Approve,End of Design
115,CS22002FB07,RES CHIP 2K 1/16W +-1%(0402)EF,CHIP,16,?,?,"R74-R76,R78,R79,R82,R124,R467,R714,R751,R786,R788,R790,R792,R794,R798",?,Comp-Approve,End of Design
116,CS22002FB07,RES CHIP 2K 1/16W +-1%(0402)EF,EMPTY,1,?,?,R40,?,Comp-Approve,End of Design
117,CS22202JB07,RES CHIP 2.2K 1/16W +-5%(0402)EF,CHIP,2,?,?,"R91,R92",?,Comp-Approve,End of Design
118,CS22212FB06,RES CHIP 2.21K 1/16W +-1%(0402)EF,EMPTY,2,?,?,"R16,R17",?,Comp-Approve,End of Design
119,CS22742FB05,RES CHIP 2.74K 1/16W +-1%(0402)EF,CHIP,1,?,?,R235,?,Comp-Approve,End of Design
120,CS22872FB03,RES CHIP 2.87K 1/16W +-1%(0402)EF,CHIP,2,?,?,"R789,R797",?,Comp-Approve,End of Design
121,CS24702FB06,RES CHIP 4.7K 1/16W +-1%(0402)EF,CHIP,129,?,?,"R9,R31,R32,R38,R44,R45,R55-R58,R61,R62,R67-R70,R72,R81,R101,R103,R115-R117,R140,R145,R149,R161,R163,R169,R188-R191,R194-R197,R212,R238-R241,R244-R262,R264,R265,R268,R269,R291,R298,R299,R307,R309,R311,R376,R387,R389,R416,R422,R428-R430,R438,R446,R452,R488,R490,R492,R521,R563,R586,R588,R591,R592,R606-R613,R615,R617,R621,R622,R624,R625,R627,R667,R683,R692,R706,R717,R730,R738-R741,R749,R758,R765,R774,R805,R806,R816,R835,R842-R844,R848,R851",?,Comp-Approve,End of Design
122,CS24702FB06,RES CHIP 4.7K 1/16W +-1%(0402)EF,EMPTY,39,?,?,"R12-R14,R34,R229,R266,R267,R284,R308,R310,R312,R388,R390,R414,R418,R455,R487,R491,R496,R593,R595,R596,R605,R623,R640,R641,R686,R687,R699,R737,R742,R753,R754,R770,R821,R828,R845,R846,R870",?,Comp-Approve,End of Design
123,CS25362FB02,RES CHIP 5.36K 1/16W +-1%(0402)EF,CHIP,1,?,?,R787,?,Comp-Approve,End of Design
124,CS25492FB02,RES CHIP 5.49K 1/16W +-1%(0402) EF,CHIP,1,?,?,PR276,?,Comp-Approve,End of Design
125,CS28202JB05,RES CHIP 8.2K 1/16W +-5% (0402) EF,CHIP,4,?,?,"R504,R619,R768,R839",?,Comp-Approve,End of Design
126,CS31002FB08,RES CHIP 10K 1/16W +-1%(0402)EF,CHIP,35,?,?,"PR241,PR242,PR244,PR255,PR498,PR500,R10,R42,R50,R59,R126,R136,R203,R204,R209,R211,R226,R227,R230,R289,R383,R464,R497,R508,R523,R618,R709,R716,R808-R811,R814,R815,R866",?,Comp-Approve,End of Design
127,CS31002FB08,RES CHIP 10K 1/16W +-1%(0402)EF,EMPTY,9,?,?,"R41,R105,R202,R228,R295,R377,R398,R712,R834",?,Comp-Approve,End of Design
128,CS31202FB04,RES CHIP 12K 1/16W +-1%(0402)EF,CHIP,2,?,?,"R830,R832",?,Comp-Approve,End of Design
129,CS31242FB02,RES CHIP 12.4K 1/16W +-1%(0402)EF,CHIP,2,?,?,"PR526,PR530",?,Comp-Approve,End of Design
130,CS31502FB05,RES CHIP 15K 1/16W +-1%(0402)EF,CHIP,1,?,?,R831,?,Comp-Approve,End of Design
131,CS31582FB02,RES CHIP 15.8K 1/16W +-1% (0402)EF,CHIP,1,?,?,R785,?,Comp-Approve,End of Design
132,CS32002FB06,RES CHIP 20K 1/16W +-1%(0402)EF,CHIP,2,?,?,"R205,R378",?,Comp-Approve,End of Design
133,CS32052FB02,RES CHIP 20.5K 1/16W +-1%(0402)EF,CHIP,1,?,?,PR525,?,Comp-Approve,End of Design
134,CS32552FB06,RES CHIP 25.5K 1/16W +-1%(0402)EF,CHIP,1,?,?,R829,?,Comp-Approve,End of Design
135,CS34702FB01,RES CHIP 47K 1/16W +-1%(0402)EF,CHIP,2,?,?,"R290,R776",?,Comp-Approve,End of Design
136,CS34992FB05,RES CHIP 49.9K 1/16W +-1%(0402)EF,CHIP,2,?,?,"R233,R234",?,Comp-Approve,End of Design
137,CS35602FB00,RES CHIP 56K 1/16W +-1%(0402)EF,CHIP,1,?,?,PR534,?,?,?
138,CS36042FB04,RES CHIP 60.4K 1/16W +-1%(0402)EF,CHIP,1,?,?,PR532,?,Comp-Approve,End of Design
139,CS39102FB06,RES CHIP 91K 1/16W +-1%(0402)EF,CHIP,1,?,?,PR527,?,?,?
140,CS41002BB08,RES CHIP 100K 1/16W +-0.1%(0402)EF,CHIP,1,?,?,PR543,?,?,?
141,CS41002FB09,RES CHIP 100K 1/16W +-1%(0402)EF,EMPTY,9,?,?,"PR245,R206,R219,R274,R296,R817-R820",?,Comp-Approve,End of Design
142,CS41002FB09,RES CHIP 100K 1/16W +-1%(0402)EF,CHIP,18,?,?,"PR522,R66,R118,R122,R193,R273,R314,R391,R392,R478,R502,R614,R620,R642,R710,R755,R778,R823",?,Comp-Approve,End of Design
143,CS41502FB04,RES CHIP 150K 1/16W +-1%(0402)EF,CHIP,1,?,?,PR496,?,Comp-Approve,End of Design
144,CS41502FB04,RES CHIP 150K 1/16W +-1%(0402)EF,EMPTY,1,?,?,R493,?,Comp-Approve,End of Design
145,CS42002FB05,RES CHIP 200K 1/16W +-1%(0402)EF,CHIP,1,?,?,R777,?,Comp-Approve,End of Design
146,CS44702FB02,RES CHIP 470K 1/16W +-1%(0402)EF,CHIP,1,?,?,R313,?,Comp-Approve,End of Design
147,CS46812FB06,RES CHIP 681K 1/16W +-1%(0402)EF,CHIP,1,?,?,PR521,?,?,?
148,CS51002FB05,RES CHIP 1M 1/16W +-1%(0402)EF,CHIP,2,?,?,"R395,R396",?,Comp-Approve,End of Design
149,CS51002FB05,RES CHIP 1M 1/16W +-1%(0402)EF,EMPTY,1,?,?,R441,?,Comp-Approve,End of Design
150,CV-10B0MZ13,IND SMD 1UH 20%11A(PCMC063T-1R0MN),IND,2,?,?,"PL31,PL33",?,?,?
151,CV-3360MZ07,"IND SMD 3.3UH,6A20%(PCMC063T-3R3MN)",IND,1,?,?,PL35,?,?,?
152,CV-47A0MZ10,IND SMD 4.7UH +-20% 10A(PCMB104E-4R7MS),IND,1,?,?,PL34,?,?,?
153,CX21SN67000,"EMI FILTER DLW21SN670HQ2L(67,320MA)",EMPTY,3,MUR,DLW21SN670HQ2L,L21-L23,?,?,?
154,CX21SN67000,"EMI FILTER DLW21SN670HQ2L(67,320MA)",IND,1,MUR,DLW21SN670HQ2L,L24,?,?,?
155,CX220TN1001,"EMI FILTER BLM18SN220TN1D(22,8000MA)",IND,4,?,?,"PL4,PL19,PL29,PL32",?,?,?
156,CX221T15000,"EMI FILTER HCB1608KF-221T15(220,1500MA)",IND,1,?,?,L20,?,?,?
157,CX5PX121001,"EMI FILTER BLM15PX121SN1D(120,2A)",IND,5,?,?,"L18,L31-L34",?,?,?
158,CX8BA470003,EMI FITTER BLM18BA470SN1(47.300MA),IND,3,?,?,L28-L30,?,Comp-Approve,End of Design
159,CX8EG121000,EMI FILTER BLM18EG121SN1D(120.2A),IND,4,?,?,"L17,L19,L26,L27",?,?,?
160,CX8PG121009,"EMI FILTER BLM18PG121SN(120,2000MA)",IND,14,?,?,L3-L16,?,?,?
161,CX8PG121009,"EMI FILTER BLM18PG121SN(120,2000MA)",EMPTY,1,?,?,L2,?,?,?
162,DFHD03MS251,"CONN SMD HEADER 3P 1R MS(P2.54, H9.3)",EMPTY,1,PRX,212-91-035BR2,J6,?,?,?
163,DFHD07MS260,"CONN DIP HEADER 7P 1R MS(P2, H6.05)",IO,1,TYC,2-2355933-7,J7,?,?,?
164,DFHD13MR071,"CONN SMD HEADER 13P 1R MR(P1,H2.9)",IO,1,ACS,50224-0130C-001,J8,?,?,?
165,DFHS05FR105,"CONN SMD MICRO USB 5P 1R FR(P0.65,H2.66)",IO,1,SIT,2UB2141-000111F,J4,?,?,?
166,DFHS09FR401,"CONN DIP USB3.0 9P 2R FR(P2.0,H7.74)",IO,1,APL,GSB311131HR,J2,?,?,?
167,DFHS11FS009,"CONN SMD HOUSING 11P 2R FS(P1,H3.28)",IO,2,BER,91920-31111LF,"J5,J10",?,?,?
168,DFHS20FR233,"CONN SMD HOUSING 20P 4R FR(P0.6,H5.9)",IO,1,FOX,3VM11207-D730-7H,J3,?,?,?
169,DFHS75FR133,"CONN SMD HOUSING 75P 2R FR(P0.5,H6.7)",IO,1,LTK,NASA0-S6730-TS67,J31,?,?,?
170,DFTJ14FR046,CONN SMD RJ45+TRANS 14P FR(H10.1)W/LED,IO,1,UDE,RS6-QU-0001,J1,?,?,?
171,DG016000006,"IC SOCKET SMD 16P(SPI,SOIC)(P1.27,H5.8)",IO,1,LTS,ACA-SPI-006-P06,J40,?,?,?
172,DHP00002F00,SWITCH SMD PUSH BUTTON DHNF-02F-T-V-T/R,MECH,3,DIP,DHNF-02F-T-V-T/R,SW1-SW3,?,?,?
173,DHPTA34W200,SWITCH TACT(TA3-4W2-Q-T/R),MECH,2,DIP,TA3-4W2-Q-T/R,"SW6,SW7",?,?,?
174,DK050TPU011,"FUSE SMD 0.5A,6V(POLY,1206L050YR)",IC,1,?,?,L1,?,?,?
175,DK110TPU003,FUSE SMD 1.1A 8V POLY(SMD1206P110TFT),IC,1,?,?,FS1,?,?,?
176,DUMMY1,QUANTA_LOGO_7X26,EMPTY,1,?,?,DM19,?,?,?
177,DUMMY2,WEEE,EMPTY,1,?,?,DM4,?,?,?
178,DUMMY3,PB-E1_SMALL,EMPTY,1,?,?,DM7,?,?,?
179,DUMMY50,HOLE_TOOLINGD125N_T2-0,EMPTY,2,?,?,"H2B1,H2B2",?,?,?
180,DUMMY8,BMC_FLASH,MECH,2,?,?,"DM2,DM5",?,?,?
181,GOLD195,GOLD_168P_ME1016810106011,EMPTY,1,APL,?,GF1,?,?,?
182,HOLE1101,HOLE_C5-5D3-2B7_NPB,EMPTY,2,?,?,"H6,H7",?,?,?
183,HOLE1211,HOLE_C6-03D3-13B6-03_NPB,EMPTY,2,?,?,"H5,H9",?,?,?
184,HOLE620,HOLE_C6D3-4B6_NPB,EMPTY,2,?,?,"H1,H2",?,?,?
185,N_A,"(USE SYM_2)TDR 3PIN,2X141MIL 1X100MIL P2P",EMPTY,6,?,?,DB1-DB6,?,?,?
186,N_A,DIFF_TEST_PAD DIP FOR FTS ONLY,EMPTY,16,?,?,"X1,X2,X5-X8,X11-X14,X17-X20,X23,X24",?,?,?
187,TMP_QAL009555K04,IC(24P) PCA9555PW(TSSOP)EP,IC,1,?,?,U40,?,?,?
188,TP24,Probe for DELTA-L measurement,EMPTY,16,?,?,"J9,J11,J12,J16,J17,J19,J20,J22-J30",?,?,?
TOTAL, , , ,1407, , , , , , 
